Altium Designer Pick and Place Locations
C:\Users\<user>\Desktop\WorkNotes\Projects\PTP\TimeCardNPI\HackDesign\WIP\ECAD\Project Outputs for Timingcard_PROJECT\Pick Place for TimeCard-DC-V9_EXP.txt

========================================================================================================================
File Design Information:

Date:       28/08/23
Time:       18:24
Revision:   Not in VersionControl
Variant:    No variations
Units used: mil

Designator Comment                 Layer       Footprint                       Center-X(mil) Center-Y(mil) Rotation Description                                                                                                                          
R186       10K_1%_0402             BottomLayer RESC1005X40X25LL05T10           454.014       -1543.654     0        ""                                                                                                                                   
R185       10K_1%_0402             BottomLayer RESC1005X40X25NL10T10           4437.008      -1543.307     0        ""                                                                                                                                   
R184       10K_1%_0402             BottomLayer RESC1005X40X25NL10T10           4373.027      -1460.630     270      ""                                                                                                                                   
R183       20K_1%_0402             BottomLayer RESC1005X40X25NL10T10           4417.323      -1460.630     270      ""                                                                                                                                   
U34        TPS2116DRLR             BottomLayer IC_TPS2116                      5677.823      -2795.343     0        "1.6-V to 5.5-V, 40-m?, 2.5-A, low-IQ, priority power multiplexer 8-SOT-5X3 -40 to 125"                                              
U32        TPS2116DRLR             BottomLayer IC_TPS2116                      5338.779      -2746.850     180      "1.6-V to 5.5-V, 40-m?, 2.5-A, low-IQ, priority power multiplexer 8-SOT-5X3 -40 to 125"                                              
U33        NCP176AMX330TCG         BottomLayer FP-711AT-MFG                    5896.524      -2799.924     0        "IC REG LINEAR 3.3V 500MA 6XDFN"                                                                                                     
R182       10K_5%_0402             BottomLayer RESC1005X40X25ML05T05           5567.587      -2755.973     0        ""                                                                                                                                   
R181       10K_5%_0402             BottomLayer RESC1005X40X25ML05T05           5421.260      -2799.213     90       ""                                                                                                                                   
R180       10K_5%_0402             BottomLayer RESC1005X40X25ML05T05           5669.949      -2728.414     0        ""                                                                                                                                   
R49        10K_5%_0402             BottomLayer RESC1005X40X25ML05T05           5342.349      -2824.808     180      ""                                                                                                                                   
C115       0.1uF_25V_0402          BottomLayer FP-0402-L_1_0_1-W_0_5_0_1-IPC_C 5962.203      -2782.794     90       "General Purpose Ceramic Capacitor, 0402, 100nF, 10%, X7R, 15%, 25V"                                                                 
C114       1uF_16V_0402            BottomLayer FP-0402-L_1_0_0_05-W_0_5-IPC_A  5962.203      -2857.597     270      None                                                                                                                                 
C113       0.1uF_25V_0402          BottomLayer FP-0402-L_1_0_1-W_0_5_0_1-IPC_C 5569.359      -2807.548     180      "General Purpose Ceramic Capacitor, 0402, 100nF, 10%, X7R, 15%, 25V"                                                                 
C112       0.1uF_25V_0402          BottomLayer FP-0402-L_1_0_1-W_0_5_0_1-IPC_C 5808.659      -2774.919     90       "General Purpose Ceramic Capacitor, 0402, 100nF, 10%, X7R, 15%, 25V"                                                                 
C111       1uF_16V_0402            BottomLayer FP-0402-L_1_0_0_05-W_0_5-IPC_A  5808.659      -2853.660     270      None                                                                                                                                 
C110       0.1uF_25V_0402          BottomLayer FP-0402-L_1_0_1-W_0_5_0_1-IPC_C 5444.711      -2718.509     90       "General Purpose Ceramic Capacitor, 0402, 100nF, 10%, X7R, 15%, 25V"                                                                 
R179       200_1%_0402             TopLayer    RESC1005X40X25NL05T05           5972.441      -1444.882     180      ""                                                                                                                                   
R178       200_1%_0402             BottomLayer RESC1005X40X25NL05T05           5889.764      -1858.268     180      ""                                                                                                                                   
R141       10K_1%_0402             BottomLayer RESC1005X40X25LL05T10           5897.304      -1602.213     270      ""                                                                                                                                   
R140       10K_1%_0402             BottomLayer RESC1005X40X25LL05T10           5897.638      -1771.653     90       ""                                                                                                                                   
D19        LTST-C191KGKT           TopLayer    FP-LTST-C191KGKT-MFG            5976.378      -1500.000     0        "LED GREEN CLEAR SMD"                                                                                                                
D12        LTST-C191KGKT           TopLayer    FP-LTST-C191KGKT-MFG            6029.528      -1861.073     0        "LED GREEN CLEAR SMD"                                                                                                                
U29        PI3A412ZHE              TopLayer    ZH16_PER                        1507.874      3.937         0        "No Description Available"                                                                                                           
U28        PI3A412ZHE              TopLayer    ZH16_PER                        4783.465      -3039.370     0        "No Description Available"                                                                                                           
U31        TMUX1072RUTR            TopLayer    FP-RUT0012A-MFG                 1897.638      -944.882      90       "IC SWITCH SPDT DUAL 12UQFN"                                                                                                         
U30        TMUX1072RUTR            TopLayer    FP-RUT0012A-MFG                 4803.150      -2657.480     0        "IC SWITCH SPDT DUAL 12UQFN"                                                                                                         
R177       49.9_1%_0402            TopLayer    RESC1005X40X25LL05T10           2000.000      -917.323      0        ""                                                                                                                                   
R176       49.9_1%_0402            TopLayer    RESC1005X40X25LL05T10           1791.339      -921.260      180      ""                                                                                                                                   
R175       49.9_1%_0402            TopLayer    RESC1005X40X25LL05T10           4826.772      -2779.528     270      ""                                                                                                                                   
R174       DNI_49.9_1%_0402        TopLayer    RESC1005X40X25LL05T10           1988.189      -1027.559     180      ""                                                                                                                                   
R173       DNI_49.9_1%_0402        TopLayer    RESC1005X40X25LL05T10           2000.000      -877.953      180      ""                                                                                                                                   
R172       DNI_49.9_1%_0402        TopLayer    RESC1005X40X25LL05T10           1795.276      -1011.811     0        ""                                                                                                                                   
R171       49.9_1%_0402            TopLayer    RESC1005X40X25LL05T10           4830.709      -2555.118     90       ""                                                                                                                                   
R170       DNI_49.9_1%_0402        TopLayer    RESC1005X40X25LL05T10           1791.339      -877.953      0        ""                                                                                                                                   
R169       DNI_49.9_1%_0402        TopLayer    RESC1005X40X25LL05T10           4799.213      -2779.528     90       ""                                                                                                                                   
R168       DNI_49.9_1%_0402        TopLayer    RESC1005X40X25LL05T10           4858.268      -2779.528     90       ""                                                                                                                                   
R167       DNI_49.9_1%_0402        TopLayer    RESC1005X40X25LL05T10           4767.717      -2555.118     270      ""                                                                                                                                   
R166       DNI_49.9_1%_0402        TopLayer    RESC1005X40X25LL05T10           4874.016      -2555.118     270      ""                                                                                                                                   
R165       DNI_27_1%_0402          TopLayer    RESC1005X40X25NL05T05           1692.913      114.173       90       ""                                                                                                                                   
R164       DNI_27_1%_0402          TopLayer    RESC1005X40X25NL05T05           1535.433      -122.047      270      ""                                                                                                                                   
R163       DNI_27_1%_0402          TopLayer    RESC1005X40X25NL05T05           1358.268      -62.992       180      ""                                                                                                                                   
R162       DNI_27_1%_0402          TopLayer    RESC1005X40X25NL05T05           1511.811      161.417       90       ""                                                                                                                                   
R161       DNI_27_1%_0402          TopLayer    RESC1005X40X25NL05T05           1598.425      114.173       90       ""                                                                                                                                   
R160       DNI_27_1%_0402          TopLayer    RESC1005X40X25NL05T05           4940.945      -3035.433     0        ""                                                                                                                                   
R159       DNI_27_1%_0402          TopLayer    RESC1005X40X25NL05T05           1625.984      -114.173      270      ""                                                                                                                                   
R158       DNI_27_1%_0402          TopLayer    RESC1005X40X25NL05T05           4866.142      -3177.165     0        ""                                                                                                                                   
R157       DNI_27_1%_0402          TopLayer    RESC1005X40X25NL05T05           1429.134      -118.110      180      ""                                                                                                                                   
R156       DNI_27_1%_0402          TopLayer    RESC1005X40X25NL05T05           4614.173      -3102.362     270      ""                                                                                                                                   
R155       DNI_27_1%_0402          TopLayer    RESC1005X40X25NL05T05           1425.197      149.606       90       ""                                                                                                                                   
R154       DNI_27_1%_0402          TopLayer    RESC1005X40X25NL05T05           4767.717      -2901.575     90       ""                                                                                                                                   
R153       DNI_27_1%_0402          TopLayer    RESC1005X40X25NL05T05           4834.646      -2897.638     90       ""                                                                                                                                   
R152       49.9_1%_0402            TopLayer    RESC1005X40X25LL05T10           1354.331      -98.425       180      ""                                                                                                                                   
R151       DNI_27_1%_0402          TopLayer    RESC1005X40X25NL05T05           4913.386      -3102.362     0        ""                                                                                                                                   
R150       49.9_1%_0402            TopLayer    RESC1005X40X25LL05T10           1586.614      -114.173      270      ""                                                                                                                                   
R149       DNI_27_1%_0402          TopLayer    RESC1005X40X25NL05T05           4720.472      -3153.543     180      ""                                                                                                                                   
R148       DNI_27_1%_0402          TopLayer    RESC1005X40X25NL05T05           4661.417      -2964.567     90       ""                                                                                                                                   
R147       49.9_1%_0402            TopLayer    RESC1005X40X25LL05T10           1645.669      114.173       90       ""                                                                                                                                   
R146       49.9_1%_0402            TopLayer    RESC1005X40X25LL05T10           4657.480      -3102.362     270      ""                                                                                                                                   
R145       49.9_1%_0402            TopLayer    RESC1005X40X25LL05T10           4913.386      -3141.732     0        ""                                                                                                                                   
R144       49.9_1%_0402            TopLayer    RESC1005X40X25LL05T10           1468.504      157.480       90       ""                                                                                                                                   
R143       49.9_1%_0402            TopLayer    RESC1005X40X25LL05T10           4885.827      -2937.008     90       ""                                                                                                                                   
R142       49.9_1%_0402            TopLayer    RESC1005X40X25LL05T10           4728.346      -2905.512     90       ""                                                                                                                                   
C109       0.1uF_25V_0402          BottomLayer FP-0402-L_1_0_1-W_0_5_0_1-IPC_C 1517.505      39.437        270      "General Purpose Ceramic Capacitor, 0402, 100nF, 10%, X7R, 15%, 25V"                                                                 
C108       0.1uF_25V_0402          BottomLayer FP-0402-L_1_0_1-W_0_5_0_1-IPC_C 4778.724      -3003.870     270      "General Purpose Ceramic Capacitor, 0402, 100nF, 10%, X7R, 15%, 25V"                                                                 
C107       0.1uF_25V_0402          BottomLayer FP-0402-L_1_0_1-W_0_5_0_1-IPC_C 1897.638      -944.882      270      "General Purpose Ceramic Capacitor, 0402, 100nF, 10%, X7R, 15%, 25V"                                                                 
C106       0.1uF_25V_0402          BottomLayer FP-0402-L_1_0_1-W_0_5_0_1-IPC_C 4803.150      -2657.480     180      "General Purpose Ceramic Capacitor, 0402, 100nF, 10%, X7R, 15%, 25V"                                                                 
C105       0.1uF_25V_0402          BottomLayer FP-0402-L_1_0_1-W_0_5_0_1-IPC_C 5733.268      -2611.220     0        "General Purpose Ceramic Capacitor, 0402, 100nF, 10%, X7R, 15%, 25V"                                                                 
C104       0.1uF_25V_0402          BottomLayer FP-0402-L_1_0_1-W_0_5_0_1-IPC_C 5659.449      -2611.193     180      "General Purpose Ceramic Capacitor, 0402, 100nF, 10%, X7R, 15%, 25V"                                                                 
C103       0.1uF_25V_0402          BottomLayer FP-0402-L_1_0_1-W_0_5_0_1-IPC_C 4976.378      -2598.425     180      "General Purpose Ceramic Capacitor, 0402, 100nF, 10%, X7R, 15%, 25V"                                                                 
C102       0.1uF_25V_0402          BottomLayer FP-0402-L_1_0_1-W_0_5_0_1-IPC_C 5076.772      -2601.362     0        "General Purpose Ceramic Capacitor, 0402, 100nF, 10%, X7R, 15%, 25V"                                                                 
C101       0.1uF_25V_0402          BottomLayer FP-0402-L_1_0_1-W_0_5_0_1-IPC_C 4972.441      -2523.622     180      "General Purpose Ceramic Capacitor, 0402, 100nF, 10%, X7R, 15%, 25V"                                                                 
C100       0.1uF_25V_0402          BottomLayer FP-0402-L_1_0_1-W_0_5_0_1-IPC_C 2141.732      -748.032      270      "General Purpose Ceramic Capacitor, 0402, 100nF, 10%, X7R, 15%, 25V"                                                                 
C99        0.1uF_25V_0402          BottomLayer FP-0402-L_1_0_1-W_0_5_0_1-IPC_C 2045.373      -750.000      270      "General Purpose Ceramic Capacitor, 0402, 100nF, 10%, X7R, 15%, 25V"                                                                 
C98        0.1uF_25V_0402          BottomLayer FP-0402-L_1_0_1-W_0_5_0_1-IPC_C 2141.732      -31.496       90       "General Purpose Ceramic Capacitor, 0402, 100nF, 10%, X7R, 15%, 25V"                                                                 
C97        0.1uF_25V_0402          BottomLayer FP-0402-L_1_0_1-W_0_5_0_1-IPC_C 2038.386      -29.528       90       "General Purpose Ceramic Capacitor, 0402, 100nF, 10%, X7R, 15%, 25V"                                                                 
C74        0.1uF_25V_0402          BottomLayer FP-0402-L_1_0_1-W_0_5_0_1-IPC_C 2094.488      27.559        90       "General Purpose Ceramic Capacitor, 0402, 100nF, 10%, X7R, 15%, 25V"                                                                 
R139       0_1%_0402               TopLayer    RESC1005X40X25LL05T05           5503.937      -3007.874     180      "Chip Resistor, 0 Ohm, 0.1 W, -55 to 155 degC, 0402 (1005 Metric), RoHS, Tape and Reel"                                              
R138       0_1%_0402               TopLayer    RESC1005X40X25LL05T05           1618.110      -590.551      180      "Chip Resistor, 0 Ohm, 0.1 W, -55 to 155 degC, 0402 (1005 Metric), RoHS, Tape and Reel"                                              
R137       4.7K_1%_0402            BottomLayer RESC1005X40X25NL10T10           5315.753      -2453.740     180      ""                                                                                                                                   
R136       4.7K_1%_0402            BottomLayer RESC1005X40X25NL10T10           5335.835      -2508.858     180      ""                                                                                                                                   
R135       4.7K_1%_0402            BottomLayer RESC1005X40X25NL10T10           5347.608      -2560.039     180      ""                                                                                                                                   
R134       4.7K_1%_0402            BottomLayer RESC1005X40X25NL10T10           2208.661      -342.990      90       ""                                                                                                                                   
R133       4.7K_1%_0402            BottomLayer RESC1005X40X25NL10T10           2153.543      -366.178      90       ""                                                                                                                                   
R132       4.7K_1%_0402            BottomLayer RESC1005X40X25NL10T10           2102.362      -387.581      90       ""                                                                                                                                   
R131       DNI_0_1%_0402           TopLayer    RESC1005X40X25LL05T05           5433.071      -3007.874     0        "Chip Resistor, 0 Ohm, 0.1 W, -55 to 155 degC, 0402 (1005 Metric), RoHS, Tape and Reel"                                              
R130       DNI_0_1%_0402           TopLayer    RESC1005X40X25LL05T05           1618.110      -543.307      180      "Chip Resistor, 0 Ohm, 0.1 W, -55 to 155 degC, 0402 (1005 Metric), RoHS, Tape and Reel"                                              
J45        2199119-3               TopLayer    FP-2199119-3-MFG                5358.268      -2772.638     180      "CONN M.2 FEMALE 67POS 0.020 GOLD"                                                                                                   
J44        2199119-3               TopLayer    FP-2199119-3-MFG                1889.764      -389.764      90       "CONN M.2 FEMALE 67POS 0.020 GOLD"                                                                                                   
C73        47uF_35V_2917           TopLayer    FP-T521X476M035ATE030-MFG       4539.370      -1480.315     90       "CAP TANT POLY 47UF 35V 2917"                                                                                                        
C72        47uF_35V_2917           TopLayer    FP-T521X476M035ATE030-MFG       972.441       122.047       180      "CAP TANT POLY 47UF 35V 2917"                                                                                                        
C71        470uF_10V_2917          TopLayer    FP-TAJE-MFG                     1035.433      -500.000      90       "470uF 10V  ±10% 500mO 2917  SMD Tantalum Capacitor"                                                                                 
R129       20K_1%_0402             BottomLayer RESC1005X40X25NL10T10           4528.543      -1460.630     270      ""                                                                                                                                   
CR1        MBRD10200CT-13          TopLayer    TO252(DPAK)_DIO                 5590.730      -366.142      270      "No Description Available"                                                                                                           
J43        47589-0001              TopLayer    MOLX-47589-0001_V               6141.732      -2800.197     90       "Right Angle Female Type AB Micro USB Connector, 30 V, 1.8 A, -30 to 85 degC, RoHS, Tape and Reel"                                   
R69        0_1%_0402               BottomLayer RESC1005X40X25LL05T05           4236.220      -1055.118     180      "Chip Resistor, 0 Ohm, 0.1 W, -55 to 155 degC, 0402 (1005 Metric), RoHS, Tape and Reel"                                              
U24        MUN12AD06-SM            TopLayer    MUN12AD06-SM_CYN                4220.472      -1160.434     180      "No Description Available"                                                                                                           
U1         MUN12AD06-SM            TopLayer    MUN12AD06-SM_CYN                1005.575      -137.795      270      "No Description Available"                                                                                                           
Y1         ABS07-32.768KHZ-T       TopLayer    FP-ABS07-MFG                    1825.162      -1234.252     90       "Crystal 32.768kHz ±20ppm (Tol) 12.5pF FUND 70k? 2-Pin CSMD T/R"                                                                     
U27        PCA9546ARGVR            TopLayer    RGV0016A_V                      3866.142      -2342.520     90       "4-Channel I2C and SMBus Multiplexer with Reset Functions, 2.3 to 5.5 V, -40 to 85 degC, 16-pin VQFN (RGV), Green (RoHS & no Sb/Br)" 
U26        TMUX1072RUTR            TopLayer    FP-RUT0012A-MFG                 3255.905      -2397.638     0        "IC SWITCH SPDT DUAL 12UQFN"                                                                                                         
U25        NCP176AMX330TCG         TopLayer    FP-711AT-MFG                    1614.173      -1015.647     0        "IC REG LINEAR 3.3V 500MA 6XDFN"                                                                                                     
SW2        219-2LPST               TopLayer    CTS-219-2LPST_V                 6074.803      -1688.976     180      "Surface Mount DIP Switch Auto Placeable, -55 to 85 degC, 4-Pin SMD, RoHS, Tube"                                                     
R128       27_1%_0402              TopLayer    RESC1005X40X25NL05T05           3724.409      -2366.142     0        ""                                                                                                                                   
R127       27_1%_0402              TopLayer    RESC1005X40X25NL05T05           3724.409      -2413.386     0        ""                                                                                                                                   
R126       27_1%_0402              TopLayer    RESC1005X40X25NL05T05           3948.819      -2192.913     180      ""                                                                                                                                   
R125       200_1%_0402             BottomLayer RESC1005X40X25NL05T05           5901.575      -2260.827     270      ""                                                                                                                                   
R124       4.7K_1%_0402            TopLayer    RESC1005X40X25NL10T10           3846.457      -2177.165     0        ""                                                                                                                                   
R123       4.7K_1%_0402            TopLayer    RESC1005X40X25NL10T10           3732.284      -2177.165     180      ""                                                                                                                                   
R122       200_1%_0402             BottomLayer RESC1005X40X25NL05T05           5846.457      -2307.087     270      ""                                                                                                                                   
R121       27_1%_0402              TopLayer    RESC1005X40X25NL05T05           3826.772      -2480.315     90       ""                                                                                                                                   
R120       4.7K_1%_0402            TopLayer    RESC1005X40X25NL10T10           3909.449      -2507.874     270      ""                                                                                                                                   
R119       4.7K_1%_0402            TopLayer    RESC1005X40X25NL10T10           3866.142      -2507.874     270      ""                                                                                                                                   
R118       4.7K_1%_0402            TopLayer    RESC1005X40X25NL10T10           4015.748      -2507.874     270      ""                                                                                                                                   
R117       4.7K_1%_0402            TopLayer    RESC1005X40X25NL10T10           3968.504      -2507.874     270      ""                                                                                                                                   
R116       4.7K_1%_0402            TopLayer    RESC1005X40X25NL10T10           4074.803      -2330.709     0        ""                                                                                                                                   
R115       4.7K_1%_0402            TopLayer    RESC1005X40X25NL10T10           4070.866      -2381.890     0        ""                                                                                                                                   
R114       4.7K_1%_0402            TopLayer    RESC1005X40X25NL10T10           4062.992      -2196.850     0        ""                                                                                                                                   
R113       4.7K_1%_0402            TopLayer    RESC1005X40X25NL10T10           4062.992      -2240.157     0        ""                                                                                                                                   
R112       200_1%_0402             BottomLayer RESC1005X40X25NL05T05           5818.898      -2418.307     270      ""                                                                                                                                   
R111       27_1%_0402              TopLayer    RESC1005X40X25NL05T05           3141.732      -2433.071     0        ""                                                                                                                                   
P5         61300411121             TopLayer    61300411121                     3212.598      -1406.693     90       "THT Vertical Pin Header WR-PHD, Pitch 2.54 mm, Single Row, 4 pins"                                                                  
P4         TSM-105-01-L-DV         TopLayer    SMTC-TSM-105-01-X-DV            6123.031      -3333.071     90       "0.025" SQ Post Header, Surface Mount, Vertical, -55 to 125 degC, 2.54 mm Pitch, 10-Pin, Male, RoHS"                                 
C39        22pF_50V_0402           TopLayer    CAPC1005X55X25ML05T05           1892.091      -1194.882     270      "Chip Capacitor, 22 pF, +/- 5%, 50 V, -55 to 125 degC, 0402 (1005 Metric), RoHS, Tape and Reel"                                      
R110       DNI_4.7K_0402           TopLayer    RESC1005X40X25LL05T05           493.514       -1155.414     180      "Chip Resistor, 4.7 KOhm, +/- 1%, 0.1 W, -55 to 155 degC, 0402 (1005 Metric), RoHS, Tape and Reel"                                   
R109       4.7K_0402               TopLayer    RESC1005X40X25LL05T05           493.514       -1080.611     0        "Chip Resistor, 4.7 KOhm, +/- 1%, 0.1 W, -55 to 155 degC, 0402 (1005 Metric), RoHS, Tape and Reel"                                   
R108       4.7K_0402               TopLayer    RESC1005X40X25LL05T05           493.514       -1116.044     0        "Chip Resistor, 4.7 KOhm, +/- 1%, 0.1 W, -55 to 155 degC, 0402 (1005 Metric), RoHS, Tape and Reel"                                   
R107       DNI_49.9_1%_0402        TopLayer    RESC1005X40X25LL05T10           2913.386      -1897.638     0        ""                                                                                                                                   
R106       DNI_49.9_1%_0402        TopLayer    RESC1005X40X25LL05T10           2933.071      -1940.945     0        ""                                                                                                                                   
R105       DNI_49.9_1%_0402        TopLayer    RESC1005X40X25LL05T10           2712.598      -1964.567     180      ""                                                                                                                                   
R104       DNI_49.9_1%_0402        TopLayer    RESC1005X40X25LL05T10           2712.598      -1921.260     180      ""                                                                                                                                   
R103       DNI_27_1%_0402          TopLayer    RESC1005X40X25NL05T05           3196.850      -3035.433     0        ""                                                                                                                                   
R102       DNI_27_1%_0402          TopLayer    RESC1005X40X25NL05T05           3200.787      -2834.646     0        ""                                                                                                                                   
R101       DNI_27_1%_0402          TopLayer    RESC1005X40X25NL05T05           3397.638      -3031.496     0        ""                                                                                                                                   
R100       DNI_27_1%_0402          TopLayer    RESC1005X40X25NL05T05           3393.701      -2811.024     0        ""                                                                                                                                   
U23        TMUX1072RUTR            TopLayer    FP-RUT0012A-MFG                 2818.898      -1952.756     90       "IC SWITCH SPDT DUAL 12UQFN"                                                                                                         
U22        TMUX1072RUTR            TopLayer    FP-RUT0012A-MFG                 3204.724      -2937.008     0        "IC SWITCH SPDT DUAL 12UQFN"                                                                                                         
U21        TMUX1072RUTR            TopLayer    FP-RUT0012A-MFG                 3393.701      -2929.134     0        "IC SWITCH SPDT DUAL 12UQFN"                                                                                                         
U20        FT234XD-R               TopLayer    FP-DFN-12-IPC_B                 6152.559      -2410.059     90       "IC USB SERIAL BASIC UART 12DFN"                                                                                                     
SW1        1571983-4               TopLayer    FP-1571983-4-MFG                6099.773      -2038.533     90       "SWITCH SLIDE DIP SPST 25MA 24V"                                                                                                     
R99        49.9_1%_0402            TopLayer    RESC1005X40X25LL05T10           2838.583      -2057.086     90       ""                                                                                                                                   
R98        49.9_1%_0402            TopLayer    RESC1005X40X25LL05T10           2858.268      -1854.331     270      ""                                                                                                                                   
R97        49.9_1%_0402            TopLayer    RESC1005X40X25LL05T10           2795.276      -2059.055     90       ""                                                                                                                                   
R96        49.9_1%_0402            TopLayer    RESC1005X40X25LL05T10           2783.465      -1854.331     270      ""                                                                                                                                   
R95        27_1%_0402              TopLayer    RESC1005X40X25NL05T05           3366.142      -2429.134     180      ""                                                                                                                                   
R94        27_1%_0402              TopLayer    RESC1005X40X25NL05T05           3169.291      -2362.205     0        ""                                                                                                                                   
R93        27_1%_0402              TopLayer    RESC1005X40X25NL05T05           3090.551      -2964.567     0        ""                                                                                                                                   
R92        27_1%_0402              TopLayer    RESC1005X40X25NL05T05           3287.402      -3005.905     90       ""                                                                                                                                   
R91        27_1%_0402              TopLayer    RESC1005X40X25NL05T05           3098.425      -2893.701     0        ""                                                                                                                                   
R90        27_1%_0402              TopLayer    RESC1005X40X25NL05T05           3279.528      -2842.520     270      ""                                                                                                                                   
R89        10K_1%_0402             BottomLayer RESC1005X40X25LL05T10           5854.331      -1968.504     0        ""                                                                                                                                   
R88        10K_1%_0402             BottomLayer RESC1005X40X25LL05T10           5838.583      -2066.929     0        ""                                                                                                                                   
R87        27_1%_0402              TopLayer    RESC1005X40X25NL05T05           3330.709      -3007.874     90       ""                                                                                                                                   
R86        27_1%_0402              TopLayer    RESC1005X40X25NL05T05           3498.032      -2960.630     180      ""                                                                                                                                   
R85        27_1%_0402              TopLayer    RESC1005X40X25NL05T05           3330.709      -2842.520     270      ""                                                                                                                                   
R84        27_1%_0402              TopLayer    RESC1005X40X25NL05T05           3505.905      -2885.827     180      ""                                                                                                                                   
R83        15K_1%_0402             TopLayer    FP-ERJ2R-MFG                    6106.299      -2566.929     0        "RES SMD 15K OHM 1% 1/10W 0402"                                                                                                      
R82        10K_1%_0402             TopLayer    RESC1005X40X25LL05T10           6110.236      -2527.559     180      ""                                                                                                                                   
R81        27_1%_0402              TopLayer    RESC1005X40X25NL05T05           6024.606      -2389.764     0        ""                                                                                                                                   
FB1        600ohm_1.3A_0603        TopLayer    FP-BLM18-0_15-t0_8-IPC_A        6023.622      -3000.000     0        "Chip Ferrite Bead, 0603, 600O @ 100MHz, 0.15O, 25%, 1.3A"                                                                           
D24        LTST-C191KGKT           TopLayer    FP-LTST-C191KGKT-MFG            6007.874      -2204.724     0        "LED GREEN CLEAR SMD"                                                                                                                
C96        0.1uF_25V_0402          BottomLayer FP-0402-L_1_0_1-W_0_5_0_1-IPC_C 2818.898      -1952.756     270      "General Purpose Ceramic Capacitor, 0402, 100nF, 10%, X7R, 15%, 25V"                                                                 
C95        0.1uF_25V_0402          BottomLayer FP-0402-L_1_0_1-W_0_5_0_1-IPC_C 3204.724      -2937.008     180      "General Purpose Ceramic Capacitor, 0402, 100nF, 10%, X7R, 15%, 25V"                                                                 
C94        0.1uF_25V_0402          BottomLayer FP-0402-L_1_0_1-W_0_5_0_1-IPC_C 3393.701      -2929.134     180      "General Purpose Ceramic Capacitor, 0402, 100nF, 10%, X7R, 15%, 25V"                                                                 
C93        0.1uF_25V_0402          BottomLayer FP-0402-L_1_0_1-W_0_5_0_1-IPC_C 6129.921      -2385.827     0        "General Purpose Ceramic Capacitor, 0402, 100nF, 10%, X7R, 15%, 25V"                                                                 
C92        0.1uF_25V_0402          BottomLayer FP-0402-L_1_0_1-W_0_5_0_1-IPC_C 6143.258      -2311.024     0        "General Purpose Ceramic Capacitor, 0402, 100nF, 10%, X7R, 15%, 25V"                                                                 
C91        10nF_50V_0402           TopLayer    FP-CC0402-MFG                   6106.299      -2610.236     180      "CAP CER 10000PF 50V X7R 0402"                                                                                                       
C90        4.7uF_16V_0402          BottomLayer FP-CL829-IPC_C                  6142.716      -3027.559     0        "Cap Ceramic 4.7uF 16V X5R ±20% SMD 0402 +85°C Paper T/R"                                                                            
C89        0.1uF_25V_0402          TopLayer    FP-0402-L_1_0_1-W_0_5_0_1-IPC_C 6145.669      -3027.559     0        "General Purpose Ceramic Capacitor, 0402, 100nF, 10%, X7R, 15%, 25V"                                                                 
C88        47pF_50V_0402           BottomLayer CAPC1005X55X25LL05T10           6027.165      -2429.914     180      ""                                                                                                                                   
C87        47pF_50V_0402           BottomLayer CAPC1005X55X25LL05T10           6027.165      -2390.544     180      ""                                                                                                                                   
C86        10nF_50V_0402           TopLayer    FP-CC0402-MFG                   5980.315      -2921.260     180      "CAP CER 10000PF 50V X7R 0402"                                                                                                       
D23        SMDJ12A                 TopLayer    FP-DO-214AB_SMC_J-Bend-MFG      5637.795      -645.669      180      "TVS DIODE 12V 19.9V DO214AB"                                                                                                        
R77        200_1%_0402             TopLayer    FP-ERJ2RK-IPC_A                 4696.850      -763.779      180      "RES SMD 200 OHM 1% 1/10W 0402"                                                                                                      
D20        LTST-C191KGKT           TopLayer    FP-LTST-C191KGKT-MFG            4545.276      -763.780      0        "LED GREEN CLEAR SMD"                                                                                                                
D22        LTST-C191KGKT           TopLayer    FP-LTST-C191KGKT-MFG            6007.874      -2267.716     0        "LED GREEN CLEAR SMD"                                                                                                                
D21        LTST-C191KGKT           TopLayer    FP-LTST-C191KGKT-MFG            6007.874      -2330.709     0        "LED GREEN CLEAR SMD"                                                                                                                
U19        INA219BIDR              TopLayer    FP-D0008A-MFG                   3805.826      -1448.819     90       "IC MONITOR PWR/CURR BIDIR 8-SOIC"                                                                                                   
U18        DNI_MYMGK00506ERSR      TopLayer    FP-MYMGK-12-MFG                 4228.346      -1488.189     270      "DC DC CONVERTER 0.7-5V"                                                                                                             
U17        INA219BIDR              TopLayer    FP-D0008A-MFG                   554.725       -508.554      0        "IC MONITOR PWR/CURR BIDIR 8-SOIC"                                                                                                   
R80        0_1%_0402               BottomLayer RESC1005X40X25LL05T05           3730.826      -1555.118     90       "Chip Resistor, 0 Ohm, 0.1 W, -55 to 155 degC, 0402 (1005 Metric), RoHS, Tape and Reel"                                              
R79        0_1%_0402               BottomLayer RESC1005X40X25LL05T05           3780.826      -1555.118     90       "Chip Resistor, 0 Ohm, 0.1 W, -55 to 155 degC, 0402 (1005 Metric), RoHS, Tape and Reel"                                              
R78        10K_1%_0402             BottomLayer RESC1005X40X25LL05T10           5838.583      -2141.732     0        ""                                                                                                                                   
R76        27_1%_0402              TopLayer    RESC1005X40X25NL05T05           3362.205      -2358.268     180      ""                                                                                                                                   
R75        DNI_27_1%_0402          TopLayer    RESC1005X40X25NL05T05           3224.409      -2507.874     0        ""                                                                                                                                   
R74        DNI_27_1%_0402          TopLayer    RESC1005X40X25NL05T05           3224.409      -2287.402     0        ""                                                                                                                                   
R73        DNI_0_1%_0402           TopLayer    RESC1005X40X25LL05T05           1829.099      -1328.740     0        "Chip Resistor, 0 Ohm, 0.1 W, -55 to 155 degC, 0402 (1005 Metric), RoHS, Tape and Reel"                                              
R72        2mOhm_1%_1206           TopLayer    RESC3216X89X64NL25T25           3941.929      -1208.661     180      ""                                                                                                                                   
R71        DNI_0_1%_0402           TopLayer    RESC1005X40X25LL05T05           1829.099      -1135.827     0        "Chip Resistor, 0 Ohm, 0.1 W, -55 to 155 degC, 0402 (1005 Metric), RoHS, Tape and Reel"                                              
R70        4.7K_1%_0402            BottomLayer RESC1005X40X25NL10T10           4163.980      -1046.434     180      ""                                                                                                                                   
R68        2K_0.5%_0402            BottomLayer RESC1005X35X25LL10T10           4024.606      -1299.213     180      ""                                                                                                                                   
R67        88.7K_0.5%_0402         BottomLayer FP-RT0402-MFG                   4102.362      -1295.276     180      "RES SMD 88.7K OHM 0.5% 1/16W"                                                                                                       
R66        0_1%_0402               BottomLayer RESC1005X40X25LL05T05           448.425       -433.554      0        "Chip Resistor, 0 Ohm, 0.1 W, -55 to 155 degC, 0402 (1005 Metric), RoHS, Tape and Reel"                                              
R65        0_1%_0402               BottomLayer RESC1005X40X25LL05T05           448.425       -483.554      0        "Chip Resistor, 0 Ohm, 0.1 W, -55 to 155 degC, 0402 (1005 Metric), RoHS, Tape and Reel"                                              
R64        0_1%_0402               BottomLayer RESC1005X40X25LL05T05           5984.252      -814.961      90       "Chip Resistor, 0 Ohm, 0.1 W, -55 to 155 degC, 0402 (1005 Metric), RoHS, Tape and Reel"                                              
R63        22_0.5%_0402            BottomLayer FP-RG1005-IPC_A                 4299.213      -1326.772     180      "Automotive Metal Thin Film Chip Resistor, 0402, 22O, 0.5%, 100ppm/°C, 0.0625W, 75V"                                                 
R62        0_1%_0402               BottomLayer RESC1005X40X25LL05T05           6033.565      -814.331      90       "Chip Resistor, 0 Ohm, 0.1 W, -55 to 155 degC, 0402 (1005 Metric), RoHS, Tape and Reel"                                              
R61        2.2K_0.5%_0402          BottomLayer RESC1005X40X25ML10T10           4257.874      -1379.921     180      ""                                                                                                                                   
R60        10K_1%_0402             BottomLayer RESC1005X40X25NL10T10           511.811       3.937         0        ""                                                                                                                                   
R59        10K_1%_0402             BottomLayer RESC1005X40X25NL10T10           700.787       7.874         180      ""                                                                                                                                   
C85        10uF_16V_0603           BottomLayer FP-0603-L_1_6_0_2-W_0_8_0-MFG   3859.566      -1350.394     180      "Multilayer Ceramic Capacitor 10uF 16V X5R 20% SMD 0603 T/R"                                                                         
C84        0.1uF_25V_0402          BottomLayer CAPC1005X56X25NL10T15           1729.392      -1225.441     90       ""                                                                                                                                   
C83        0.1uF_25V_0402          TopLayer    FP-0402-L_1_0_1-W_0_5_0_1-IPC_C 3906.538      -1119.899     90       "General Purpose Ceramic Capacitor, 0402, 100nF, 10%, X7R, 15%, 25V"                                                                 
C82        1uF_16V_0402            TopLayer    FP-0402-L_1_0_0_05-W_0_5-IPC_A  3548.664      -1198.819     180      None                                                                                                                                 
C81        2.2uF_16V_0402          TopLayer    FP-C1005-050-0_05-IPC_A         3548.664      -1131.890     180      "Multilayer Ceramic Capacitors 2.2µF ±10% 16V X5R SMD 0402"                                                                          
C80        10uF_16V_0603           TopLayer    FP-0603-L_1_6_0_2-W_0_8_0-MFG   3832.677      -1118.110     90       "Multilayer Ceramic Capacitor 10uF 16V X5R 20% SMD 0603 T/R"                                                                         
C79        100uF_16V_2917          TopLayer    FP-T495D107K016ATE125-MFG       3464.173      -1338.583     0        "CAP TANT 100UF 10% 16V 2917"                                                                                                        
C78        47uF_16V_1206           TopLayer    FP-C3216-160-0_2-MFG            3688.976      -1118.110     180      "Multilayer Ceramic Capacitors 47uF ±20% 16V X5R SMD 1206"                                                                           
C77        4.7uF_50V_1206          TopLayer    FP-GRM31C-0_2-e0_3_0_8-IPC_C    4599.379      -1251.968     0        "Chip Multilayer Ceramic Capacitors for General Purpose, 1206, 4.7uF, X7R, 15%, 10%, 50V"                                            
C76        4.7uF_50V_1206          TopLayer    FP-GRM31C-0_2-e0_3_0_8-IPC_C    4433.071      -1173.228     90       "Chip Multilayer Ceramic Capacitors for General Purpose, 1206, 4.7uF, X7R, 15%, 10%, 50V"                                            
C75        100uF_16V_2917          TopLayer    FP-T495D107K016ATE125-MFG       4574.803      -1019.685     270      "CAP TANT 100UF 10% 16V 2917"                                                                                                        
C70        0.1uF_25V_0402          BottomLayer FP-0402-L_1_0_1-W_0_5_0_1-IPC_C 3779.528      -2329.724     0        "General Purpose Ceramic Capacitor, 0402, 100nF, 10%, X7R, 15%, 25V"                                                                 
C69        0.1uF_25V_0402          BottomLayer FP-0402-L_1_0_1-W_0_5_0_1-IPC_C 3255.905      -2397.638     180      "General Purpose Ceramic Capacitor, 0402, 100nF, 10%, X7R, 15%, 25V"                                                                 
C68        22pF_50V_0402           TopLayer    CAPC1005X55X25ML05T05           1892.091      -1293.307     90       "Chip Capacitor, 22 pF, +/- 5%, 50 V, -55 to 125 degC, 0402 (1005 Metric), RoHS, Tape and Reel"                                      
R58        4.7K_0402               BottomLayer RESC1005X40X25LL05T05           1592.879      -1214.567     180      "Chip Resistor, 4.7 KOhm, +/- 1%, 0.1 W, -55 to 155 degC, 0402 (1005 Metric), RoHS, Tape and Reel"                                   
R57        4.7K_0402               BottomLayer RESC1005X40X25LL05T05           1580.084      -1170.276     270      "Chip Resistor, 4.7 KOhm, +/- 1%, 0.1 W, -55 to 155 degC, 0402 (1005 Metric), RoHS, Tape and Reel"                                   
R56        DNI_4.7K_0402           BottomLayer RESC1005X40X25LL05T05           1565.320      -1372.047     0        "Chip Resistor, 4.7 KOhm, +/- 1%, 0.1 W, -55 to 155 degC, 0402 (1005 Metric), RoHS, Tape and Reel"                                   
R55        4.7K_0402               BottomLayer RESC1005X40X25LL05T05           1592.879      -1250.000     0        "Chip Resistor, 4.7 KOhm, +/- 1%, 0.1 W, -55 to 155 degC, 0402 (1005 Metric), RoHS, Tape and Reel"                                   
R54        0_1%_0402               BottomLayer RESC1005X40X25LL05T05           1588.942      -1289.370     180      "Chip Resistor, 0 Ohm, 0.1 W, -55 to 155 degC, 0402 (1005 Metric), RoHS, Tape and Reel"                                              
R53        4.7K_0402               BottomLayer RESC1005X40X25LL05T05           1640.123      -1364.173     0        "Chip Resistor, 4.7 KOhm, +/- 1%, 0.1 W, -55 to 155 degC, 0402 (1005 Metric), RoHS, Tape and Reel"                                   
R52        4.7K_0402               BottomLayer RESC1005X40X25LL05T05           1640.123      -1297.244     270      "Chip Resistor, 4.7 KOhm, +/- 1%, 0.1 W, -55 to 155 degC, 0402 (1005 Metric), RoHS, Tape and Reel"                                   
R51        4.7K_0402               BottomLayer RESC1005X40X25LL05T05           1631.711      -1175.966     180      "Chip Resistor, 4.7 KOhm, +/- 1%, 0.1 W, -55 to 155 degC, 0402 (1005 Metric), RoHS, Tape and Reel"                                   
R50        4.7K_0402               BottomLayer RESC1005X40X25LL05T05           1580.084      -1321.851     180      "Chip Resistor, 4.7 KOhm, +/- 1%, 0.1 W, -55 to 155 degC, 0402 (1005 Metric), RoHS, Tape and Reel"                                   
C67        0.1uF_25V_0402          BottomLayer CAPC1005X56X25NL10T15           1684.414      -1170.276     270      ""                                                                                                                                   
C66        0.1uF_25V_0402          BottomLayer CAPC1005X56X25NL10T15           3862.641      -1413.386     0        ""                                                                                                                                   
C65        1uF_0402                BottomLayer FP-0402-L_1_0_0_05-W_0_5-IPC_C  1514.139      -1242.126     180      None                                                                                                                                 
C64        0.1uF                   BottomLayer CAPC1608X87X45ML20T05           5582.677      -3401.575     0        C0603X104K5RACAUTO                                                                                                                   
C57        0.1uF                   BottomLayer CAPC1608X87X45ML20T05           5661.417      -3192.913     180      C0603X104K5RACAUTO                                                                                                                   
C56        10uF                    BottomLayer FP-MK212BG-MFG                  5570.866      -3303.150     180      None                                                                                                                                 
C55        10uF                    BottomLayer FP-MK212BG-MFG                  5661.417      -3098.425     0        None                                                                                                                                 
C54        0.1uF                   BottomLayer CAPC1608X87X45ML20T05           1205.807      -474.013      0        C0603X104K5RACAUTO                                                                                                                   
C43        0.1uF                   BottomLayer CAPC1608X87X45ML20T05           1629.921      -456.693      90       C0603X104K5RACAUTO                                                                                                                   
C42        10uF                    BottomLayer FP-MK212BG-MFG                  1254.036      -745.745      0        None                                                                                                                                 
C41        10uF                    BottomLayer FP-MK212BG-MFG                  1486.321      -457.181      270      None                                                                                                                                 
R48        DNI_0_1%_0402           BottomLayer RESC1005X40X25LL05T05           452.756       -1488.189     0        "Chip Resistor, 0 Ohm, 0.1 W, -55 to 155 degC, 0402 (1005 Metric), RoHS, Tape and Reel"                                              
SKT10      0332-0-43-80-18-27-10-0 TopLayer    SolderSocket                    1622.205      -3342.520     90       "Solder socket for pin headers"                                                                                                      
SKT9       0332-0-43-80-18-27-10-0 TopLayer    SolderSocket                    2181.102      -3236.220     90       "Solder socket for pin headers"                                                                                                      
SKT8       0332-0-43-80-18-27-10-0 TopLayer    SolderSocket                    1742.205      -3342.520     90       "Solder socket for pin headers"                                                                                                      
SKT7       0332-0-43-80-18-27-10-0 TopLayer    SolderSocket                    2181.102      -1637.795     90       "Solder socket for pin headers"                                                                                                      
SKT6       0332-0-43-80-18-27-10-0 TopLayer    SolderSocket                    582.677       -2437.008     90       "Solder socket for pin headers"                                                                                                      
SKT5       0332-0-43-80-18-27-10-0 TopLayer    SolderSocket                    582.677       -3236.220     90       "Solder socket for pin headers"                                                                                                      
SKT4       0332-0-43-80-18-27-10-0 TopLayer    SolderSocket                    2098.425      -3342.520     90       "Solder socket for pin headers"                                                                                                      
SKT3       0332-0-43-80-18-27-10-0 TopLayer    SolderSocket                    1980.315      -3342.520     90       "Solder socket for pin headers"                                                                                                      
SKT2       0332-0-43-80-18-27-10-0 TopLayer    SolderSocket                    582.677       -1637.795     90       "Solder socket for pin headers"                                                                                                      
SKT1       0332-0-43-80-18-27-10-0 TopLayer    SolderSocket                    1862.205      -3342.520     90       "Solder socket for pin headers"                                                                                                      
P1         TSW-105-05-L-S          TopLayer    SMTC-TSW-105-05-X-S             2980.315      -1355.118     90       "0.025" SQ Post Header, Through-hole, Vertical, -55 to 125 degC, 2.54 mm Pitch, 5-Pin, Male, RoHS"                                   
R47        DNI_0_5%_1206           TopLayer    RESC3116X65X50ML20T20           2702.756      -1525.591     0        ""                                                                                                                                   
J38        39-30-0040              TopLayer    FP-39-30-0040-MFG               5779.095      -8.051        90       "CONN HEADER R/A 4POS 4.2MM"                                                                                                         
R46        DNI_0_5%_1206           TopLayer    RESC3116X65X50ML20T20           2702.756      -1289.370     0        ""                                                                                                                                   
R45        0_5%_1206               TopLayer    RESC3116X65X50ML20T20           2702.756      -1411.417     0        ""                                                                                                                                   
R44        DNI_0_5%_1206           TopLayer    RESC3116X65X50ML20T20           5992.126      -342.520      270      ""                                                                                                                                   
J37        "Single FPGA Conn"      TopLayer    SingleFPGAConn                  3510.871      -3298.899     90       ""                                                                                                                                   
J36        "Single FPGA Conn"      TopLayer    SingleFPGAConn                  2610.818      -2553.373     0        ""                                                                                                                                   
J35        "Single FPGA Conn"      TopLayer    SingleFPGAConn                  3510.871      -1817.690     270      ""                                                                                                                                   
J34        "Single FPGA Conn"      TopLayer    SingleFPGAConn                  4485.728      -2553.373     180      ""                                                                                                                                   
J31        SA53_Header             TopLayer    SA53_Header                     2170.668      -2436.800     180      ""                                                                                                                                   
J13        "GNSS Header 16-pin"    TopLayer    GNSS_Header_16-pin              5332.189      -3201.673     90       ""                                                                                                                                   
J6         "GNSS Header 16-pin"    TopLayer    GNSS_Header_16-pin              1382.973      -457.181      0        ""                                                                                                                                   
R43        27_1%_0402              TopLayer    RESC1005X40X25NL05T05           6024.606      -2429.134     0        ""                                                                                                                                   
R42        27_1%_0402              TopLayer    RESC1005X40X25NL05T05           6122.047      -2287.402     180      ""                                                                                                                                   
D10        LTST-C191KGKT           TopLayer    FP-LTST-C191KGKT-MFG            287.402       49.213        0        "LED GREEN CLEAR SMD"                                                                                                                
D9         LTST-C191KGKT           TopLayer    FP-LTST-C191KGKT-MFG            287.402       118.110       0        "LED GREEN CLEAR SMD"                                                                                                                
D3         LTST-C191KGKT           TopLayer    FP-LTST-C191KGKT-MFG            287.402       187.008       0        "LED GREEN CLEAR SMD"                                                                                                                
U16        NC7WV125K8X             TopLayer    SOP50P310X90-8N                 157.480       -3417.323     180      "Integrated Circuit"                                                                                                                 
U12        NC7WV125K8X             TopLayer    SOP50P310X90-8N                 208.661       -2318.898     180      "Integrated Circuit"                                                                                                                 
U11        NC7WV125K8X             TopLayer    SOP50P310X90-8N                 208.661       -2889.764     180      "Integrated Circuit"                                                                                                                 
U8         NC7WV125K8X             TopLayer    SOP50P310X90-8N                 208.661       -1842.520     180      "Integrated Circuit"                                                                                                                 
U6         IS32FL3207              TopLayer    IS32FL3207                      849.814       -1238.091     0        ""                                                                                                                                   
R41        4.7K                    TopLayer    RESC1608X55X30NL15T15           613.593       -1336.516     0        "Precision Thick Film Chip Resistor, 4.7 KOhm, +/- 1%, -55 to 155 degC, 0603 (1608 Metric), RoHS, Tape and Reel ERJ-3EKF4701V"       
R40        DNI_100k                TopLayer    FP-RC0603-0_55-MFG              615.562       -1080.611     0        "RES SMD 100K OHM 1% 1/10W 0603"                                                                                                     
R39        "200 OHM"               BottomLayer RESC1608X55X30NL15T15           287.402       -43.307       180      ERJ-3EKF2000V                                                                                                                        
R38        "200 OHM"               BottomLayer RESC1608X55X30NL15T15           287.402       25.590        180      ERJ-3EKF2000V                                                                                                                        
R36        "200 OHM"               BottomLayer RESC1608X55X30NL15T15           287.402       94.488        180      ERJ-3EKF2000V                                                                                                                        
R35        "200 OHM"               BottomLayer RESC1608X55X30NL15T15           287.402       163.386       180      ERJ-3EKF2000V                                                                                                                        
R34        49.9R                   TopLayer    RESC1608X55X25NL10T15           11.811        -3381.890     90       "General Purpose Chip Resistor, 49.9 Ohm, +/- 1%, -55 to 155 degC, 0603 (1608 Metric), RoHS, Tape and Reel"                          
R33        49.9R                   TopLayer    RESC1608X55X25NL10T15           114.173       -2232.284     90       "General Purpose Chip Resistor, 49.9 Ohm, +/- 1%, -55 to 155 degC, 0603 (1608 Metric), RoHS, Tape and Reel"                          
R32        4.7K_1%_0402            TopLayer    RESC1005X40X25NL10T10           -11.811       -3476.378     90       ""                                                                                                                                   
R31        4.7K_1%_0402            TopLayer    RESC1005X40X25NL10T10           204.724       -3500.000     0        ""                                                                                                                                   
P3         "EXT GPIO"              TopLayer    HDR2X6_CEN                      6144.488      -1231.890     270      "Header, 6-Pin, Dual row"                                                                                                            
J4         1909763-1               TopLayer    TECO-1909763-1_V                169.745       -3169.291     270      "Ultra Miniature Coaxial Connector Jack, 60 V, 50 Ohm, -40 to 90 degC, RoHS, Tape and Reel"                                          
J2         1909763-1               TopLayer    TECO-1909763-1_V                169.745       -2106.299     270      "Ultra Miniature Coaxial Connector Jack, 60 V, 50 Ohm, -40 to 90 degC, RoHS, Tape and Reel"                                          
J3         1909763-1               TopLayer    TECO-1909763-1_V                169.745       -2627.953     270      "Ultra Miniature Coaxial Connector Jack, 60 V, 50 Ohm, -40 to 90 degC, RoHS, Tape and Reel"                                          
J1         1909763-1               TopLayer    TECO-1909763-1_V                169.745       -1573.323     270      "Ultra Miniature Coaxial Connector Jack, 60 V, 50 Ohm, -40 to 90 degC, RoHS, Tape and Reel"                                          
D18        155124M173200           TopLayer    155124M173200                   -190.453      -3413.386     90       "LED (Multiple)"                                                                                                                     
D17        155124M173200           TopLayer    155124M173200                   -190.453      -2885.827     90       "LED (Multiple)"                                                                                                                     
D16        155124M173200           TopLayer    155124M173200                   -190.453      -2350.394     90       "LED (Multiple)"                                                                                                                     
D15        155124M173200           TopLayer    155124M173200                   -190.453      -1822.835     90       "LED (Multiple)"                                                                                                                     
C40        0.1uF                   TopLayer    CAPC1608X87X45ML20T05           639.184       -1238.091     90       C0603X104K5RACAUTO                                                                                                                   
C38        1uF                     TopLayer    FP-C0603C105K3PACTU-MFG         574.223       -1232.185     270      "CAP CER 1UF 25V X5R 0603"                                                                                                           
C33        0.1uF_25V_0402          BottomLayer FP-0402-L_1_0_1-W_0_5_0_1-IPC_C 1586.614      -999.899      90       "General Purpose Ceramic Capacitor, 0402, 100nF, 10%, X7R, 15%, 25V"                                                                 
C32        1uF_16V_0402            TopLayer    FP-0402-L_1_0_0_05-W_0_5-IPC_A  1531.496      -1015.748     270      None                                                                                                                                 
R37        10K                     BottomLayer RESC1608X55X30LL15T20           4322.372      -2019.685     90       "Chip Resistor, 10 KOhm, +/- 1%, 0.1 W, -55 to 155 degC, 0603 (1608 Metric), RoHS, Tape and Reel RMCF0603FT10K0"                     
U15        RCB-F9T-1               TopLayer    GNSS                            5489.669      -3201.673     90       "MOD, GPS"                                                                                                                           
C37        0.1uF                   BottomLayer CAPC1608X87X45ML20T05           5330.709      -3389.764     180      C0603X104K5RACAUTO                                                                                                                   
C36        0.1uF                   BottomLayer CAPC1608X87X45ML20T05           5334.646      -3007.874     180      C0603X104K5RACAUTO                                                                                                                   
C35        10uF                    BottomLayer FP-MK212BG-MFG                  5332.189      -3288.373     0        None                                                                                                                                 
C34        10uF                    BottomLayer FP-MK212BG-MFG                  5332.189      -3122.724     0        None                                                                                                                                 
D2         8240136                 TopLayer    SOT143-4L                       -9.842        -2874.016     90       "TVS Diode WE-TVS-HS, VRWM=3.3V"                                                                                                     
D1         8240136                 TopLayer    SOT143-4L                       -9.843        -1828.740     90       "TVS Diode WE-TVS-HS, VRWM=3.3V"                                                                                                     
R27        160_0.5%_0402           BottomLayer FP-RT0402-MFG                   568.241       -335.630      90       "RES SMD 160 OHM 0.5% 1/16W 0402"                                                                                                    
R26        1.2K_0.5%_0402          BottomLayer RESC1005X40X25ML10T10           584.646       -273.622      0        ""                                                                                                                                   
U10        MAC-SA5X                TopLayer    SA53                            1416.043      -2470.157     180      "MOD, MAC, MAC-SA5X, ATOMIC CLOCK"                                                                                                   
R14        4.7K_1%_0402            TopLayer    RESC1005X40X25NL10T10           248.031       -1925.197     0        ""                                                                                                                                   
U14        BME280                  TopLayer    FP-BME280-MFG                   1318.193      -1283.499     270      "SENSOR PRESSURE HUMIDITY TEMP"                                                                                                      
U13        BNO055                  TopLayer    FP-BNO055-MFG                   1632.249      -1265.748     0        "IMU ACCEL/GYRO/MAG I2C 28LGA"                                                                                                       
U4         DS90LV028AQMA           TopLayer    M08A_L                          2066.929      -1220.472     90       "Automotive LVDS Dual Differential Line Receiver, 8-pin Narrow SOIC"                                                                 
U3         DS90LV027AQMA           TopLayer    M08A_N                          2307.087      -1228.347     90       "Automotive LVDS Dual Differential Driver, 8-pin Narrow SOIC"                                                                        
R25        49.9R                   TopLayer    RESC1608X55X25NL10T15           129.921       -1755.906     180      "General Purpose Chip Resistor, 49.9 Ohm, +/- 1%, -55 to 155 degC, 0603 (1608 Metric), RoHS, Tape and Reel"                          
R17        4.7K_1%_0402            BottomLayer RESC1005X40X25NL10T10           251.969       -2948.819     0        ""                                                                                                                                   
R13        27_1%_0402              TopLayer    RESC1005X40X25NL05T05           6224.409      -2283.465     0        ""                                                                                                                                   
R12        110R                    BottomLayer RESC1609X50X30NL10T20           2015.748      -1307.087     0        ""                                                                                                                                   
R11        4.7K                    BottomLayer RESC1608X55X25LL10T15           2358.268      -1318.898     180      "Chip Resistor, 4.7 KOhm, +/- 1%, 0.1 W, -55 to 155 degC, 0603 (1608 Metric), RoHS, Tape and Reel RC0603FR-074K7L"                   
R10        4.7K                    BottomLayer RESC1608X55X25LL10T15           2255.905      -1326.772     0        "Chip Resistor, 4.7 KOhm, +/- 1%, 0.1 W, -55 to 155 degC, 0603 (1608 Metric), RoHS, Tape and Reel RC0603FR-074K7L"                   
C31        0.1uF                   TopLayer    CAPC1608X87X45ML20T05           1312.150      -1104.624     0        C0603X104K5RACAUTO                                                                                                                   
C30        0.1uF                   TopLayer    CAPC1608X87X45ML20T05           1312.785      -1161.468     0        C0603X104K5RACAUTO                                                                                                                   
C29        0.1uF_25V_0402          TopLayer    FP-0402-L_1_0_1-W_0_5_0_1-IPC_C 98.425        -2377.953     180      "General Purpose Ceramic Capacitor, 0402, 100nF, 10%, X7R, 15%, 25V"                                                                 
C28        0.1uF_25V_0402          TopLayer    FP-0402-L_1_0_1-W_0_5_0_1-IPC_C 70.866        -3492.126     180      "General Purpose Ceramic Capacitor, 0402, 100nF, 10%, X7R, 15%, 25V"                                                                 
C27        0.1uF_25V_0402          TopLayer    FP-0402-L_1_0_1-W_0_5_0_1-IPC_C 141.732       -2984.252     270      "General Purpose Ceramic Capacitor, 0402, 100nF, 10%, X7R, 15%, 25V"                                                                 
C26        0.1uF_25V_0402          TopLayer    FP-0402-L_1_0_1-W_0_5_0_1-IPC_C 118.110       -1933.071     180      "General Purpose Ceramic Capacitor, 0402, 100nF, 10%, X7R, 15%, 25V"                                                                 
C24        0.1uF                   BottomLayer CAPC1608X87X45ML20T05           1952.756      -1118.110     180      C0603X104K5RACAUTO                                                                                                                   
C23        0.1uF                   BottomLayer CAPC1608X87X45ML20T05           2200.787      -1381.890     0        C0603X104K5RACAUTO                                                                                                                   
AN1        RF2-49B-T-00-50-G-HDW   TopLayer    AMPH-901-143-6RFX_V             -84.645       -1573.323     180      "Coaxial connector, 50 Ohm, -65 to 165 degC, 5-Pin THD, RoHS, Bulk"                                                                  
AN3        RF2-49B-T-00-50-G-HDW   TopLayer    AMPH-901-143-6RFX_V             -84.646       -2636.299     180      "Coaxial connector, 50 Ohm, -65 to 165 degC, 5-Pin THD, RoHS, Bulk"                                                                  
AN2        RF2-49B-T-00-50-G-HDW   TopLayer    AMPH-901-143-6RFX_V             -84.646       -2104.803     180      "Coaxial connector, 50 Ohm, -65 to 165 degC, 5-Pin THD, RoHS, Bulk"                                                                  
AN4        RF2-49B-T-00-50-G-HDW   TopLayer    AMPH-901-143-6RFX_V             -84.645       -3167.811     180      "Coaxial connector, 50 Ohm, -65 to 165 degC, 5-Pin THD, RoHS, Bulk"                                                                  
U7         AT24MAC402-STUM-T       TopLayer    FP-5TS1-IPC_C                   4283.002      -1968.504     270      "IC EEPROM 2K I2C 1MHZ SOT23-5"                                                                                                      
C25        0.1uF                   BottomLayer CAPC1608X87X45ML20T05           4259.380      -1972.441     270      C0603X104K5RACAUTO                                                                                                                   
R16        4.7K_1%_0402            BottomLayer RESC1005X40X25NL10T10           181.102       -2944.882     90       ""                                                                                                                                   
R15        4.7K_1%_0402            BottomLayer RESC1005X40X25NL10T10           86.614        -1913.386     90       ""                                                                                                                                   
R5         4.7K_1%_0402            BottomLayer RESC1005X40X25NL10T10           911.575       -169.291      0        ""                                                                                                                                   
U9         RCB-F9T                 TopLayer    GNSS                            1382.973      -614.662      0        "MOD, GPS"                                                                                                                           
U5         DNI_MYMGK00506ERSR      TopLayer    FP-MYMGK-12-MFG                 614.173       -165.354      90       "DC DC CONVERTER 0.7-5V"                                                                                                             
U2         INA219BIDR              TopLayer    FP-D0008A-MFG                   6059.055      -728.346      90       "IC MONITOR PWR/CURR BIDIR 8-SOIC"                                                                                                   
R30        4.7K_1%_0402            TopLayer    RESC1005X40X25NL10T10           51.181        -2346.457     0        ""                                                                                                                                   
R29        4.7K_1%_0402            TopLayer    RESC1005X40X25NL10T10           251.969       -2393.701     0        ""                                                                                                                                   
R28        49.9R                   TopLayer    RESC1608X55X25NL10T15           118.110       -2807.087     180      "General Purpose Chip Resistor, 49.9 Ohm, +/- 1%, -55 to 155 degC, 0603 (1608 Metric), RoHS, Tape and Reel"                          
R24        ERJ-2GE0R00X            TopLayer    RESC1005X04N                    1326.772      -3523.622     0        "RES, 0. OHM, 1%, 1/16W, TF, AEC-Q200, 0402"                                                                                         
R23        ERJ-2GE0R00X            TopLayer    RESC1005X04N                    1326.772      -3480.315     0        "RES, 0. OHM, 1%, 1/16W, TF, AEC-Q200, 0402"                                                                                         
R22        ERJ-3EKF4701V           BottomLayer RESC1608X50N                    2905.512      -2736.220     0        "RES, 4.7K, 1%, 1/10W, TF, 0603"                                                                                                     
R21        CRCW080533R0FKEA        TopLayer    RESC2012X50N                    5252.756      -3562.963     0        "RES, 33 OHM, 1%, 1/8W, TF, 0805"                                                                                                    
R20        CRCW080533R0FKEA        TopLayer    RESC2012X50N                    5697.638      -3566.900     0        "RES, 33 OHM, 1%, 1/8W, TF, 0805"                                                                                                    
R19        CRCW080533R0FKEA        TopLayer    RESC2012X50N                    4853.780      -3566.198     0        "RES, 33 OHM, 1%, 1/8W, TF, 0805"                                                                                                    
R18        CRCW080533R0FKEA        TopLayer    RESC2012X50N                    4408.898      -3558.324     0        "RES, 33 OHM, 1%, 1/8W, TF, 0805"                                                                                                    
R9         20K_1%_0402             BottomLayer RESC1005X40X25NL10T10           631.890       -57.087       0        ""                                                                                                                                   
R8         2mOhm_1%_1206           TopLayer    RESC3216X89X64NL25T25           822.835       -401.575      0        ""                                                                                                                                   
R7         2mOhm_1%_1206           TopLayer    RESC3216X89X64NL25T25           5949.803      -523.622      0        ""                                                                                                                                   
R6         20K_1%_0402             BottomLayer RESC1005X40X25NL10T10           549.212       -57.087       0        ""                                                                                                                                   
R4         0_1%_0402               BottomLayer RESC1005X40X25LL05T05           911.575       -131.295      180      "Chip Resistor, 0 Ohm, 0.1 W, -55 to 155 degC, 0402 (1005 Metric), RoHS, Tape and Reel"                                              
R3         0_1%_0402               BottomLayer RESC1005X40X25LL05T05           1106.299      -303.150      180      "Chip Resistor, 0 Ohm, 0.1 W, -55 to 155 degC, 0402 (1005 Metric), RoHS, Tape and Reel"                                              
R2         147K_1%_0402            BottomLayer RESC1005X40X25ML05T10           1110.236      -236.220      270      ""                                                                                                                                   
R1         200_1%_0402             TopLayer    FP-ERJ2RK-IPC_A                 952.756       -996.063      0        "RES SMD 200 OHM 1% 1/10W 0402"                                                                                                      
P2         PCIex4                  TopLayer    PCIE_4LANE_EDGE                 2161.417      -4004.518     0        "PCIE x4 Edge Connector,OrCAD Symbol,NC"                                                                                             
F1         FUSE_0603_5.00A         TopLayer    FUSM1608X60N                    5905.512      -381.890      270      "FUSE SLOW 5.00A 32V M 0603"                                                                                                         
D14        155124M173200           TopLayer    155124M173200                   -190.453      -1084.646     90       "LED (Multiple)"                                                                                                                     
D13        155124M173200           TopLayer    155124M173200                   -190.453      -651.575      90       "LED (Multiple)"                                                                                                                     
D11        LTST-C191KGKT           TopLayer    FP-LTST-C191KGKT-MFG            287.402       -19.685       0        "LED GREEN CLEAR SMD"                                                                                                                
D8         BAT54SW                 TopLayer    SOT65P210X110-3N                5071.654      -3562.963     0        "DIO, SCHOTTKY, BAT54S, DUAL SERIES, 30V, 200MA, SC-70"                                                                              
D7         BAT54SW                 TopLayer    SOT65P210X110-3N                5521.457      -3560.994     0        "DIO, SCHOTTKY, BAT54S, DUAL SERIES, 30V, 200MA, SC-70"                                                                              
D6         BAT54SW                 TopLayer    SOT65P210X110-3N                4687.441      -3566.198     0        "DIO, SCHOTTKY, BAT54S, DUAL SERIES, 30V, 200MA, SC-70"                                                                              
D5         BAT54SW                 TopLayer    SOT65P210X110-3N                4239.607      -3558.324     0        "DIO, SCHOTTKY, BAT54S, DUAL SERIES, 30V, 200MA, SC-70"                                                                              
D4         LTST-C191KGKT           TopLayer    FP-LTST-C191KGKT-MFG            952.756       -921.260      180      "LED GREEN CLEAR SMD"                                                                                                                
C63        0.1uF                   TopLayer    CAPC1608X87X45ML20T05           2530.816      -1178.207     270      C0603X104K5RACAUTO                                                                                                                   
C62        CAP_0805_10UF_25V       TopLayer    CAPC2012X14N                    2624.559      -1167.323     90       "CAP, CER, 10.UF, 25V, 10%, X5R, 0805"                                                                                               
C61        0.1uF                   BottomLayer CAPC1608X87X45ML20T05           1254.036      -654.032      180      C0603X104K5RACAUTO                                                                                                                   
C60        10uF                    BottomLayer FP-MK212BG-MFG                  1220.472      -362.205      180      None                                                                                                                                 
C59        0.1uF                   BottomLayer CAPC1608X87X45ML20T05           1468.504      -803.150      0        C0603X104K5RACAUTO                                                                                                                   
C58        10uF                    BottomLayer FP-MK212BG-MFG                  1480.328      -710.724      180      None                                                                                                                                 
C53        CAP_0402_0.1UF_50V      BottomLayer CAPC1005X06N                    2734.410      -3806.000     90       "CAP, CER, 0.1UF, 50V, 10%, X7R, AEC-Q200, 0402"                                                                                     
C52        CAP_0402_0.1UF_50V      BottomLayer CAPC1005X06N                    2694.410      -3806.000     90       "CAP, CER, 0.1UF, 50V, 10%, X7R, AEC-Q200, 0402"                                                                                     
C51        CAP_0402_0.1UF_50V      BottomLayer CAPC1005X06N                    2569.410      -3806.000     90       "CAP, CER, 0.1UF, 50V, 10%, X7R, AEC-Q200, 0402"                                                                                     
C50        CAP_0402_0.1UF_50V      BottomLayer CAPC1005X06N                    2534.410      -3806.000     90       "CAP, CER, 0.1UF, 50V, 10%, X7R, AEC-Q200, 0402"                                                                                     
C49        CAP_0402_0.1UF_50V      BottomLayer CAPC1005X06N                    2419.410      -3806.000     90       "CAP, CER, 0.1UF, 50V, 10%, X7R, AEC-Q200, 0402"                                                                                     
C48        CAP_0402_0.1UF_50V      BottomLayer CAPC1005X06N                    2379.410      -3806.000     90       "CAP, CER, 0.1UF, 50V, 10%, X7R, AEC-Q200, 0402"                                                                                     
C47        CAP_0402_0.1UF_50V      BottomLayer CAPC1005X06N                    2226.410      -3806.000     90       "CAP, CER, 0.1UF, 50V, 10%, X7R, AEC-Q200, 0402"                                                                                     
C46        CAP_0402_0.1UF_50V      BottomLayer CAPC1005X06N                    2183.410      -3806.000     90       "CAP, CER, 0.1UF, 50V, 10%, X7R, AEC-Q200, 0402"                                                                                     
C45        CAP_0402_0.1UF_50V      BottomLayer CAPC1005X06N                    2104.410      -3806.000     90       "CAP, CER, 0.1UF, 50V, 10%, X7R, AEC-Q200, 0402"                                                                                     
C44        CAP_0402_0.1UF_50V      BottomLayer CAPC1005X06N                    2064.410      -3806.000     90       "CAP, CER, 0.1UF, 50V, 10%, X7R, AEC-Q200, 0402"                                                                                     
C22        10uF_16V_0603           BottomLayer FP-0603-L_1_6_0_2-W_0_8_0-MFG   645.276       -559.735      90       "Multilayer Ceramic Capacitor 10uF 16V X5R 20% SMD 0603 T/R"                                                                         
C21        0.1uF_25V_0402          BottomLayer CAPC1005X56X25NL10T15           590.158       -559.735      270      ""                                                                                                                                   
C20        10uF_16V_0603           BottomLayer FP-0603-L_1_6_0_2-W_0_8_0-MFG   6110.236      -649.606      180      "Multilayer Ceramic Capacitor 10uF 16V X5R 20% SMD 0603 T/R"                                                                         
C19        0.1uF_25V_0402          BottomLayer CAPC1005X56X25NL10T15           6110.236      -598.425      0        ""                                                                                                                                   
C18        0.1uF_25V_0402          BottomLayer FP-0402-L_1_0_1-W_0_5_0_1-IPC_C 1086.614      -461.987      270      "General Purpose Ceramic Capacitor, 0402, 100nF, 10%, X7R, 15%, 25V"                                                                 
C17        1uF_16V_0402            BottomLayer FP-0402-L_1_0_0_05-W_0_5-IPC_A  956.693       -771.654      0        None                                                                                                                                 
C16        2.2uF_16V_0402          BottomLayer FP-C1005-050-0_05-IPC_A         960.630       -468.504      270      "Multilayer Ceramic Capacitors 2.2µF ±10% 16V X5R SMD 0402"                                                                          
C15        10uF_16V_0603           BottomLayer FP-0603-L_1_6_0_2-W_0_8_0-MFG   1019.685      -464.567      270      "Multilayer Ceramic Capacitor 10uF 16V X5R 20% SMD 0603 T/R"                                                                         
C14        100uF_16V_2917          TopLayer    FP-T495D107K016ATE125-MFG       956.693       -771.654      180      "CAP TANT 100UF 10% 16V 2917"                                                                                                        
C13        47uF_16V_1206           TopLayer    FP-C3216-160-0_2-MFG            811.116       -617.227      180      "Multilayer Ceramic Capacitors 47uF ±20% 16V X5R SMD 1206"                                                                           
C12        4.7uF_50V_1206          TopLayer    FP-GRM31C-0_2-e0_3_0_8-IPC_C    307.087       -98.425       180      "Chip Multilayer Ceramic Capacitors for General Purpose, 1206, 4.7uF, X7R, 15%, 10%, 50V"                                            
C11        4.7uF_50V_1206          TopLayer    FP-GRM31C-0_2-e0_3_0_8-IPC_C    307.087       -188.976      180      "Chip Multilayer Ceramic Capacitors for General Purpose, 1206, 4.7uF, X7R, 15%, 10%, 50V"                                            
C10        100uF_16V_2917          TopLayer    FP-T495D107K016ATE125-MFG       606.299       125.984       0        "CAP TANT 100UF 10% 16V 2917"                                                                                                        
C9         2.2uF_16V_0402          BottomLayer FP-C1005-050-0_05-IPC_A         1531.496      -1015.748     270      "Multilayer Ceramic Capacitors 2.2µF ±10% 16V X5R SMD 0402"                                                                          
C8         10uF_16V_0603           TopLayer    FP-0603-L_1_6_0_2-W_0_8_0-MFG   1484.252      -1015.798     270      "Multilayer Ceramic Capacitor 10uF 16V X5R 20% SMD 0603 T/R"                                                                         
C7         2.2uF_16V_0402          TopLayer    FP-C1005-050-0_05-IPC_A         1681.102      -1019.685     270      "Multilayer Ceramic Capacitors 2.2µF ±10% 16V X5R SMD 0402"                                                                          
C6         10uF_16V_0603           BottomLayer FP-0603-L_1_6_0_2-W_0_8_0-MFG   1649.606      -1015.748     270      "Multilayer Ceramic Capacitor 10uF 16V X5R 20% SMD 0603 T/R"                                                                         
C5         2.2uF_16V_0402          BottomLayer FP-C1005-050-0_05-IPC_A         4157.480      -1244.094     180      "Multilayer Ceramic Capacitors 2.2µF ±10% 16V X5R SMD 0402"                                                                          
C4         470uF_10V_2917          TopLayer    FP-TAJE-MFG                     3464.567      -1539.370     0        "470uF 10V  ±10% 500mO 2917  SMD Tantalum Capacitor"                                                                                 
C3         2.2uF_16V_0402          BottomLayer FP-C1005-050-0_05-IPC_A         1129.921      -161.417      180      "Multilayer Ceramic Capacitors 2.2µF ±10% 16V X5R SMD 0402"                                                                          
C2         0.1uF                   TopLayer    CAPC1608X87X45ML20T05           6118.110      -409.449      270      C0603X104K5RACAUTO                                                                                                                   
C1         CAP_0805_10UF_25V       TopLayer    CAPC2012X14N                    6208.661      -393.701      90       "CAP, CER, 10.UF, 25V, 10%, X5R, 0805"                                                                                               
